# BASEBOARD_FAB2 (Tioga Pass) — schematic netlist excerpt (pin names and nets, part order shuffled) for the footprints in the layout excerpt that follows; sources: Cadence DE-HDL packaged netlist, KiCad conversion of Wiwynn_Tioga_Pass_MB.brd

EU4E1  IR354XX  IR35411 IC  pkg SM  page 202
  VOS  = PVCCIN_CPU0
  LGND  = GND
  VCC  = VR_PVCCIN_CPU0_PH1_VCIN
  VDRV  = P5V_STBY
  PGND(0)  = GND
  GL(0)  = TP_PVCCIN_CPU0_PH1_GL_0
  PGND(1)  = GND
  SW  = VR_PVCCIN_CPU0_PHASE1
  VIN(0)  = VR_FET_SW_P12V_STBY_PVCCIN_CPU0
  VIN(1)  = VR_FET_SW_P12V_STBY_PVCCIN_CPU0
  NC  = NC
  PHASE  = VR_PVCCIN_CPU0_PH1_PHASE
  BOOST  = VR_PVCCIN_CPU0_PH1_BOOT_R
  PWM  = VR_PVCCIN_CPU0_PWM1
  EN  = P5V_STBY
  TOUT_FLT  = A_TSENSE_PVCCIN_CPU0
  OCSET  = VR_PVCCIN_CPU0_PH1_OCSET
  IOUT  = ISENSE_PVCCIN_CPU0_PH1_IMON
  REFIN  = VR_PVCCIN_CPU0_AIREF1
  PGND(2)  = GND
  GL(1)  = TP_PVCCIN_CPU0_PH1_GL_1

(kicad_pcb
	(version 20260206)
	(generator "pcbnew")
	(generator_version "10.0")
	(general
		(thickness 1.6)
		(legacy_teardrops no)
	)
	(paper "A4")
	(title_block
		(title "Wiwynn_Tioga_Pass_MB.brd")
		(comment 1 "Tioga Pass / footprints 806-806 of 4770")
	)
	(layers
		(0 "F.Cu" signal "TOP")
		(4 "In1.Cu" signal "L2GND")
		(6 "In2.Cu" signal "L3")
		(8 "In3.Cu" signal "L4GND")
		(10 "In4.Cu" signal "L5")
		(12 "In5.Cu" signal "L6GND")
		(14 "In6.Cu" signal "L7VCC")
		(16 "In7.Cu" signal "L8VCC")
		(18 "In8.Cu" signal "L9GND")
		(20 "In9.Cu" signal "L10")
		(22 "In10.Cu" signal "L11GND")
		(24 "In11.Cu" signal "L12")
		(26 "In12.Cu" signal "L13GND")
		(2 "B.Cu" signal "BOTTOM")
		(9 "F.Adhes" user "F.Adhesive")
		(11 "B.Adhes" user "B.Adhesive")
		(13 "F.Paste" user "Package Geometry/Pastemask Top")
		(15 "B.Paste" user "Package Geometry/Pastemask Bottom")
		(5 "F.SilkS" user "Ref Des/Silkscreen Top")
		(7 "B.SilkS" user "Ref Des/Silkscreen Bottom")
		(1 "F.Mask" user "Board Geometry/Soldermask Top")
		(3 "B.Mask" user "Board Geometry/Soldermask Bottom")
		(17 "Dwgs.User" user "User.Drawings")
		(19 "Cmts.User" user "User.Comments")
		(21 "Eco1.User" user "User.Eco1")
		(23 "Eco2.User" user "User.Eco2")
		(25 "Edge.Cuts" user "Board Geometry/Outline")
		(27 "Margin" user)
		(31 "F.CrtYd" user "Package Geometry/Place Bound Top")
		(29 "B.CrtYd" user "Package Geometry/Place Bound Bottom")
		(35 "F.Fab" user "Ref Des/Assembly Top")
		(33 "B.Fab" user "Ref Des/Assembly Bottom")
	)
	(footprint ""
		(layer "F.Cu")
		(at 198.925434 -57.039764 90)
		(property "Reference" "EU4E1"
			(at 3.360166 -1.643634 0)
			(unlocked yes)
			(layer "F.SilkS")
			(effects
				(font
					(size 0.7874 0.5842)
					(thickness 0.1524)
				)
			)
		)
		(property "Value" ""
			(at 0 0 90)
			(layer "F.Fab")
			(effects
				(font
					(size 1.27 1.27)
				)
			)
		)
		(duplicate_pad_numbers_are_jumpers no)
		(fp_line
			(start 2.9718 -3.5052)
			(end 2.9718 3.429)
			(stroke
				(width 0.1524)
				(type default)
			)
			(layer "F.SilkS")
		)
		(fp_line
			(start -3.0099 -3.5052)
			(end 2.9718 -3.5052)
			(stroke
				(width 0.1524)
				(type default)
			)
			(layer "F.SilkS")
		)
		(fp_line
			(start 2.9718 3.429)
			(end -3.0099 3.429)
			(stroke
				(width 0.1524)
				(type default)
			)
			(layer "F.SilkS")
		)
		(fp_line
			(start -3.0099 3.429)
			(end -3.0099 -3.5052)
			(stroke
				(width 0.1524)
				(type default)
			)
			(layer "F.SilkS")
		)
		(fp_circle
			(center -3.057398 -2.678684)
			(end -3.057398 -2.551684)
			(stroke
				(width 0.254)
				(type default)
			)
			(fill no)
			(layer "F.SilkS")
		)
		(fp_poly
			(pts
				(xy -2.9972 -3.4925) (xy -2.9972 -2.6924) (xy -2.1971 -3.4925)
			)
			(stroke
				(width 0)
				(type default)
			)
			(fill yes)
			(layer "F.SilkS")
		)
		(fp_poly
			(pts
				(xy -2.549906 -3.050032) (xy -2.549906 3.050032) (xy 2.549906 3.050032) (xy 2.549906 -3.050032)
			)
			(stroke
				(width 0)
				(type default)
			)
			(fill no)
			(layer "F.CrtYd")
		)
		(fp_line
			(start 2.549906 -3.050032)
			(end 2.549906 3.050032)
			(stroke
				(width 0.1)
				(type default)
			)
			(layer "F.Fab")
		)
		(fp_line
			(start -2.549906 -3.050032)
			(end 2.549906 -3.050032)
			(stroke
				(width 0.1)
				(type default)
			)
			(layer "F.Fab")
		)
		(fp_line
			(start 2.549906 3.050032)
			(end -2.549906 3.050032)
			(stroke
				(width 0.1)
				(type default)
			)
			(layer "F.Fab")
		)
		(fp_line
			(start -2.549906 3.050032)
			(end -2.549906 -3.050032)
			(stroke
				(width 0.1)
				(type default)
			)
			(layer "F.Fab")
		)
		(fp_circle
			(center -3.057398 -2.678684)
			(end -3.057398 -2.551684)
			(stroke
				(width 0.254)
				(type default)
			)
			(fill no)
			(layer "F.Fab")
		)
		(pad "1" smd rect
			(at -2.39522 -2.279904 90)
			(size 0.7112 0.254)
			(layers "F.Cu" "F.Mask" "F.Paste")
			(net "PVCCIN_CPU0")
		)
		(pad "2" smd rect
			(at -2.39522 -1.83007 90)
			(size 0.7112 0.254)
			(layers "F.Cu" "F.Mask" "F.Paste")
			(net "GND")
		)
		(pad "3" smd rect
			(at -2.39522 -1.379982 90)
			(size 0.7112 0.254)
			(layers "F.Cu" "F.Mask" "F.Paste")
			(net "VR_PVCCIN_CPU0_PH1_VCIN")
		)
		(pad "4" smd rect
			(at -2.39522 -0.929894 90)
			(size 0.7112 0.254)
			(layers "F.Cu" "F.Mask" "F.Paste")
			(net "P5V_STBY")
		)
		(pad "5" smd rect
			(at -2.39522 -0.48006 90)
			(size 0.7112 0.254)
			(layers "F.Cu" "F.Mask" "F.Paste")
			(net "GND")
		)
		(pad "6" smd rect
			(at -2.39522 -0.029972 90)
			(size 0.7112 0.254)
			(layers "F.Cu" "F.Mask" "F.Paste")
			(net "TP_PVCCIN_CPU0_PH1_GL_0")
		)
		(pad "7" smd custom
			(at 0.016764 1.145032 90)
			(size 0.53975 0.53975)
			(layers "F.Cu" "F.Mask" "F.Paste")
			(net "GND")
			(options
				(clearance outline)
				(anchor circle)
			)
			(primitives
				(gr_poly
					(pts
						(xy -2.7051 1.0795) (xy -2.7051 -0.3683) (xy -0.9271 -0.3683) (xy -0.9271 -1.0795) (xy 2.7051 -1.0795)
						(xy 2.7051 1.0795)
					)
					(width 0)
					(fill yes)
				)
			)
		)
		(pad "10" smd rect
			(at -0.008382 2.874772 90)
			(size 4.3434 0.6096)
			(layers "F.Cu" "F.Mask" "F.Paste")
			(net "VR_PVCCIN_CPU0_PHASE1")
		)
		(pad "25" smd rect
			(at 1.548384 -1.283208 90)
			(size 2.3368 2.0066)
			(layers "F.Cu" "F.Mask" "F.Paste")
			(net "VR_FET_SW_P12V_STBY_PVCCIN_CPU0")
		)
		(pad "30" smd rect
			(at 2.050034 -2.895092 90)
			(size 0.254 0.7112)
			(layers "F.Cu" "F.Mask" "F.Paste")
			(net "VR_FET_SW_P12V_STBY_PVCCIN_CPU0")
		)
		(pad "31" smd rect
			(at 1.599946 -2.895092 90)
			(size 0.254 0.7112)
			(layers "F.Cu" "F.Mask" "F.Paste")
			(net "Net_361")
		)
		(pad "32" smd rect
			(at 1.150112 -2.895092 90)
			(size 0.254 0.7112)
			(layers "F.Cu" "F.Mask" "F.Paste")
			(net "VR_PVCCIN_CPU0_PH1_PHASE")
		)
		(pad "33" smd rect
			(at 0.700024 -2.895092 90)
			(size 0.254 0.7112)
			(layers "F.Cu" "F.Mask" "F.Paste")
			(net "VR_PVCCIN_CPU0_PH1_BOOT_R")
		)
		(pad "34" smd rect
			(at 0.249936 -2.895092 90)
			(size 0.254 0.7112)
			(layers "F.Cu" "F.Mask" "F.Paste")
			(net "VR_PVCCIN_CPU0_PWM1")
		)
		(pad "35" smd rect
			(at -0.199898 -2.895092 90)
			(size 0.254 0.7112)
			(layers "F.Cu" "F.Mask" "F.Paste")
			(net "P5V_STBY")
		)
		(pad "36" smd rect
			(at -0.649986 -2.895092 90)
			(size 0.254 0.7112)
			(layers "F.Cu" "F.Mask" "F.Paste")
			(net "A_TSENSE_PVCCIN_CPU0")
		)
		(pad "37" smd rect
			(at -1.100074 -2.895092 90)
			(size 0.254 0.7112)
			(layers "F.Cu" "F.Mask" "F.Paste")
			(net "VR_PVCCIN_CPU0_PH1_OCSET")
		)
		(pad "38" smd rect
			(at -1.549908 -2.895092 90)
			(size 0.254 0.7112)
			(layers "F.Cu" "F.Mask" "F.Paste")
			(net "ISENSE_PVCCIN_CPU0_PH1_IMON")
		)
		(pad "39" smd rect
			(at -1.999996 -2.895092 90)
			(size 0.254 0.7112)
			(layers "F.Cu" "F.Mask" "F.Paste")
			(net "VR_PVCCIN_CPU0_AIREF1")
		)
		(pad "40" smd rect
			(at -0.871728 -1.283208 90)
			(size 1.8034 2.0066)
			(layers "F.Cu" "F.Mask" "F.Paste")
			(net "GND")
		)
		(pad "41" smd rect
			(at -1.533906 0.247904 90)
			(size 0.508 0.3556)
			(layers "F.Cu" "F.Mask" "F.Paste")
			(net "TP_PVCCIN_CPU0_PH1_GL_1")
		)
	)
)
